(kicad_pcb
	(version 20260206)
	(generator "pcbnew")
	(generator_version "10.0")
	(general
		(thickness 1.6)
		(legacy_teardrops no)
	)
	(paper "A4")
	(title_block
		(title "04192023_DAF0TMB3IC0_F0TG_MB_C_brd_V02_OCP.brd")
		(comment 1 "Grand Teton / footprints 6923-6931 of 8354")
	)
	(layers
		(0 "F.Cu" signal "TOP")
		(4 "In1.Cu" signal "GND")
		(6 "In2.Cu" signal "IN1")
		(8 "In3.Cu" signal "GND1")
		(10 "In4.Cu" signal "IN2")
		(12 "In5.Cu" signal "GND2")
		(14 "In6.Cu" signal "IN3")
		(16 "In7.Cu" signal "GND3")
		(18 "In8.Cu" signal "VCC")
		(20 "In9.Cu" signal "VCC1")
		(22 "In10.Cu" signal "GND4")
		(24 "In11.Cu" signal "IN4")
		(26 "In12.Cu" signal "GND5")
		(28 "In13.Cu" signal "IN5")
		(30 "In14.Cu" signal "GND6")
		(32 "In15.Cu" signal "IN6")
		(34 "In16.Cu" signal "GND7")
		(2 "B.Cu" signal "BOTTOM")
		(9 "F.Adhes" user "F.Adhesive")
		(11 "B.Adhes" user "B.Adhesive")
		(13 "F.Paste" user "Package Geometry/Pastemask Top")
		(15 "B.Paste" user "Package Geometry/Pastemask Bottom")
		(5 "F.SilkS" user "Ref Des/Silkscreen Top")
		(7 "B.SilkS" user "Ref Des/Silkscreen Bottom")
		(1 "F.Mask" user "Board Geometry/Soldermask Top")
		(3 "B.Mask" user "Board Geometry/Soldermask Bottom")
		(17 "Dwgs.User" user "User.Drawings")
		(19 "Cmts.User" user "User.Comments")
		(21 "Eco1.User" user "User.Eco1")
		(23 "Eco2.User" user "User.Eco2")
		(25 "Edge.Cuts" user "Board Geometry/Outline")
		(27 "Margin" user)
		(31 "F.CrtYd" user "Package Geometry/Place Bound Top")
		(29 "B.CrtYd" user "Package Geometry/Place Bound Bottom")
		(35 "F.Fab" user "Ref Des/Assembly Top")
		(33 "B.Fab" user "Ref Des/Assembly Bottom")
	)
	(footprint ""
		(layer "B.Cu")
		(at 450.431408 -389.600694 -90)
		(property "Reference" "PC6586_2"
			(at 0 0 90)
			(layer "B.SilkS")
			(hide yes)
			(effects
				(font
					(size 1.27 1.27)
				)
				(justify mirror)
			)
		)
		(property "Value" ""
			(at 0 0 90)
			(layer "B.Fab")
			(effects
				(font
					(size 1.27 1.27)
				)
				(justify mirror)
			)
		)
		(duplicate_pad_numbers_are_jumpers no)
		(fp_line
			(start -1.524 0.762)
			(end 1.524 0.762)
			(stroke
				(width 0.1524)
				(type default)
			)
			(layer "B.SilkS")
		)
		(fp_line
			(start 1.524 0.762)
			(end 1.524 -0.762)
			(stroke
				(width 0.1524)
				(type default)
			)
			(layer "B.SilkS")
		)
		(fp_line
			(start -1.524 -0.762)
			(end -1.524 0.762)
			(stroke
				(width 0.1524)
				(type default)
			)
			(layer "B.SilkS")
		)
		(fp_line
			(start 1.524 -0.762)
			(end -1.524 -0.762)
			(stroke
				(width 0.1524)
				(type default)
			)
			(layer "B.SilkS")
		)
		(fp_line
			(start -1.1049 0.724916)
			(end -1.1049 -0.724916)
			(stroke
				(width 0.1)
				(type default)
			)
			(layer "B.Fab")
		)
		(fp_line
			(start 1.1049 0.724916)
			(end -1.1049 0.724916)
			(stroke
				(width 0.1)
				(type default)
			)
			(layer "B.Fab")
		)
		(fp_line
			(start -1.1049 -0.724916)
			(end 1.1049 -0.724916)
			(stroke
				(width 0.1)
				(type default)
			)
			(layer "B.Fab")
		)
		(fp_line
			(start 1.1049 -0.724916)
			(end 1.1049 0.724916)
			(stroke
				(width 0.1)
				(type default)
			)
			(layer "B.Fab")
		)
		(pad "1" smd rect
			(at 0.889 0 270)
			(size 1.016 1.27)
			(layers "B.Cu" "B.Mask" "B.Paste")
			(net "P0V9_CPU0_RT_2D")
		)
		(pad "2" smd rect
			(at -0.889 0 270)
			(size 1.016 1.27)
			(layers "B.Cu" "B.Mask" "B.Paste")
			(net "GND")
		)
	)
	(footprint ""
		(layer "B.Cu")
		(at 316.578234 -395.148562 90)
		(property "Reference" "C545"
			(at 0 0 90)
			(layer "B.SilkS")
			(hide yes)
			(effects
				(font
					(size 1.27 1.27)
				)
				(justify mirror)
			)
		)
		(property "Value" ""
			(at 0 0 90)
			(layer "B.Fab")
			(effects
				(font
					(size 1.27 1.27)
				)
				(justify mirror)
			)
		)
		(duplicate_pad_numbers_are_jumpers no)
		(fp_line
			(start 0.299974 -0.150114)
			(end -0.299974 -0.150114)
			(stroke
				(width 0.1)
				(type default)
			)
			(layer "B.Fab")
		)
		(fp_line
			(start -0.299974 -0.150114)
			(end -0.299974 0.150114)
			(stroke
				(width 0.1)
				(type default)
			)
			(layer "B.Fab")
		)
		(fp_line
			(start 0.299974 0.150114)
			(end 0.299974 -0.150114)
			(stroke
				(width 0.1)
				(type default)
			)
			(layer "B.Fab")
		)
		(fp_line
			(start -0.299974 0.150114)
			(end 0.299974 0.150114)
			(stroke
				(width 0.1)
				(type default)
			)
			(layer "B.Fab")
		)
		(pad "1" smd rect
			(at 0.2667 0 270)
			(size 0.3048 0.381)
			(layers "B.Cu" "B.Mask" "B.Paste")
			(net "P0V9_CPU0_RT0_2A_2D")
		)
		(pad "2" smd rect
			(at -0.2667 0 270)
			(size 0.3048 0.381)
			(layers "B.Cu" "B.Mask" "B.Paste")
			(net "GND")
		)
	)
	(footprint ""
		(layer "B.Cu")
		(at 416.200082 -416.899344 90)
		(property "Reference" "C6625"
			(at 0 0 90)
			(layer "B.SilkS")
			(hide yes)
			(effects
				(font
					(size 1.27 1.27)
				)
				(justify mirror)
			)
		)
		(property "Value" ""
			(at 0 0 90)
			(layer "B.Fab")
			(effects
				(font
					(size 1.27 1.27)
				)
				(justify mirror)
			)
		)
		(duplicate_pad_numbers_are_jumpers no)
		(fp_line
			(start 0.299974 -0.150114)
			(end -0.299974 -0.150114)
			(stroke
				(width 0.1)
				(type default)
			)
			(layer "B.Fab")
		)
		(fp_line
			(start -0.299974 -0.150114)
			(end -0.299974 0.150114)
			(stroke
				(width 0.1)
				(type default)
			)
			(layer "B.Fab")
		)
		(fp_line
			(start 0.299974 0.150114)
			(end 0.299974 -0.150114)
			(stroke
				(width 0.1)
				(type default)
			)
			(layer "B.Fab")
		)
		(fp_line
			(start -0.299974 0.150114)
			(end 0.299974 0.150114)
			(stroke
				(width 0.1)
				(type default)
			)
			(layer "B.Fab")
		)
		(pad "1" smd rect
			(at 0.2667 0 270)
			(size 0.3048 0.381)
			(layers "B.Cu" "B.Mask" "B.Paste")
			(net "P5E_CPU0_P3_TX_BUF_C_DP<14>")
		)
		(pad "2" smd rect
			(at -0.2667 0 270)
			(size 0.3048 0.381)
			(layers "B.Cu" "B.Mask" "B.Paste")
			(net "P5E_CPU0_P3_TX_BUF_DP<14>")
		)
	)
	(footprint ""
		(layer "B.Cu")
		(at 301.562008 -389.444738)
		(property "Reference" "C7010"
			(at 0 0 0)
			(layer "B.SilkS")
			(hide yes)
			(effects
				(font
					(size 1.27 1.27)
				)
				(justify mirror)
			)
		)
		(property "Value" ""
			(at 0 0 0)
			(layer "B.Fab")
			(effects
				(font
					(size 1.27 1.27)
				)
				(justify mirror)
			)
		)
		(duplicate_pad_numbers_are_jumpers no)
		(fp_line
			(start -1.524 -0.762)
			(end -1.524 0.762)
			(stroke
				(width 0.1524)
				(type default)
			)
			(layer "B.SilkS")
		)
		(fp_line
			(start -1.524 0.762)
			(end 1.524 0.762)
			(stroke
				(width 0.1524)
				(type default)
			)
			(layer "B.SilkS")
		)
		(fp_line
			(start 1.524 -0.762)
			(end -1.524 -0.762)
			(stroke
				(width 0.1524)
				(type default)
			)
			(layer "B.SilkS")
		)
		(fp_line
			(start 1.524 0.762)
			(end 1.524 -0.762)
			(stroke
				(width 0.1524)
				(type default)
			)
			(layer "B.SilkS")
		)
		(fp_line
			(start -1.1049 -0.724916)
			(end 1.1049 -0.724916)
			(stroke
				(width 0.1)
				(type default)
			)
			(layer "B.Fab")
		)
		(fp_line
			(start -1.1049 0.724916)
			(end -1.1049 -0.724916)
			(stroke
				(width 0.1)
				(type default)
			)
			(layer "B.Fab")
		)
		(fp_line
			(start 1.1049 -0.724916)
			(end 1.1049 0.724916)
			(stroke
				(width 0.1)
				(type default)
			)
			(layer "B.Fab")
		)
		(fp_line
			(start 1.1049 0.724916)
			(end -1.1049 0.724916)
			(stroke
				(width 0.1)
				(type default)
			)
			(layer "B.Fab")
		)
		(pad "1" smd rect
			(at 0.889 0)
			(size 1.016 1.27)
			(layers "B.Cu" "B.Mask" "B.Paste")
			(net "P0V9_CPU0_RT0_2A")
		)
		(pad "2" smd rect
			(at -0.889 0)
			(size 1.016 1.27)
			(layers "B.Cu" "B.Mask" "B.Paste")
			(net "GND")
		)
	)
	(footprint ""
		(layer "B.Cu")
		(at 52.74564 -426.003212 90)
		(property "Reference" "R3512"
			(at 0 0 90)
			(layer "B.SilkS")
			(hide yes)
			(effects
				(font
					(size 1.27 1.27)
				)
				(justify mirror)
			)
		)
		(property "Value" ""
			(at 0 0 90)
			(layer "B.Fab")
			(effects
				(font
					(size 1.27 1.27)
				)
				(justify mirror)
			)
		)
		(duplicate_pad_numbers_are_jumpers no)
		(fp_line
			(start 0.7874 -0.4064)
			(end -0.7874 -0.4064)
			(stroke
				(width 0.1524)
				(type default)
			)
			(layer "B.SilkS")
		)
		(fp_line
			(start -0.7874 -0.4064)
			(end -0.7874 0.4064)
			(stroke
				(width 0.1524)
				(type default)
			)
			(layer "B.SilkS")
		)
		(fp_line
			(start 0.7874 0.4064)
			(end 0.7874 -0.4064)
			(stroke
				(width 0.1524)
				(type default)
			)
			(layer "B.SilkS")
		)
		(fp_line
			(start -0.7874 0.4064)
			(end 0.7874 0.4064)
			(stroke
				(width 0.1524)
				(type default)
			)
			(layer "B.SilkS")
		)
		(fp_line
			(start 0.67945 -0.305054)
			(end 0.12065 -0.305054)
			(stroke
				(width 0.1)
				(type default)
			)
			(layer "B.Fab")
		)
		(fp_line
			(start 0.12065 -0.305054)
			(end 0.12065 -0.2794)
			(stroke
				(width 0.1)
				(type default)
			)
			(layer "B.Fab")
		)
		(fp_line
			(start -0.12065 -0.3048)
			(end -0.67945 -0.3048)
			(stroke
				(width 0.1)
				(type default)
			)
			(layer "B.Fab")
		)
		(fp_line
			(start -0.67945 -0.3048)
			(end -0.67945 0.3048)
			(stroke
				(width 0.1)
				(type default)
			)
			(layer "B.Fab")
		)
		(fp_line
			(start 0.12065 -0.2794)
			(end -0.12065 -0.2794)
			(stroke
				(width 0.1)
				(type default)
			)
			(layer "B.Fab")
		)
		(fp_line
			(start -0.12065 -0.2794)
			(end -0.12065 -0.3048)
			(stroke
				(width 0.1)
				(type default)
			)
			(layer "B.Fab")
		)
		(fp_line
			(start 0.12065 0.2794)
			(end 0.12065 0.3048)
			(stroke
				(width 0.1)
				(type default)
			)
			(layer "B.Fab")
		)
		(fp_line
			(start -0.120396 0.2794)
			(end 0.12065 0.2794)
			(stroke
				(width 0.1)
				(type default)
			)
			(layer "B.Fab")
		)
		(fp_line
			(start 0.67945 0.3048)
			(end 0.67945 -0.305054)
			(stroke
				(width 0.1)
				(type default)
			)
			(layer "B.Fab")
		)
		(fp_line
			(start 0.12065 0.3048)
			(end 0.67945 0.3048)
			(stroke
				(width 0.1)
				(type default)
			)
			(layer "B.Fab")
		)
		(fp_line
			(start -0.120396 0.3048)
			(end -0.120396 0.2794)
			(stroke
				(width 0.1)
				(type default)
			)
			(layer "B.Fab")
		)
		(fp_line
			(start -0.67945 0.3048)
			(end -0.120396 0.3048)
			(stroke
				(width 0.1)
				(type default)
			)
			(layer "B.Fab")
		)
		(pad "1" smd circle
			(at 0.40005 0 270)
			(size 0 0)
			(layers "B.Cu" "B.Mask" "B.Paste")
			(net "P3V3_AUX")
		)
		(pad "2" smd circle
			(at -0.40005 0 270)
			(size 0 0)
			(layers "B.Cu" "B.Mask" "B.Paste")
			(net "FM_GPU_PWRGD")
		)
	)
	(footprint ""
		(layer "B.Cu")
		(at 58.65241 -151.779224 180)
		(property "Reference" "PC87"
			(at 0 0 0)
			(layer "B.SilkS")
			(hide yes)
			(effects
				(font
					(size 1.27 1.27)
				)
				(justify mirror)
			)
		)
		(property "Value" ""
			(at 0 0 0)
			(layer "B.Fab")
			(effects
				(font
					(size 1.27 1.27)
				)
				(justify mirror)
			)
		)
		(duplicate_pad_numbers_are_jumpers no)
		(fp_line
			(start 1.524 0.762)
			(end 1.524 -0.762)
			(stroke
				(width 0.1524)
				(type default)
			)
			(layer "B.SilkS")
		)
		(fp_line
			(start 1.524 -0.762)
			(end -1.524 -0.762)
			(stroke
				(width 0.1524)
				(type default)
			)
			(layer "B.SilkS")
		)
		(fp_line
			(start -1.524 0.762)
			(end 1.524 0.762)
			(stroke
				(width 0.1524)
				(type default)
			)
			(layer "B.SilkS")
		)
		(fp_line
			(start -1.524 -0.762)
			(end -1.524 0.762)
			(stroke
				(width 0.1524)
				(type default)
			)
			(layer "B.SilkS")
		)
		(fp_line
			(start 1.1049 0.724916)
			(end -1.1049 0.724916)
			(stroke
				(width 0.1)
				(type default)
			)
			(layer "B.Fab")
		)
		(fp_line
			(start 1.1049 -0.724916)
			(end 1.1049 0.724916)
			(stroke
				(width 0.1)
				(type default)
			)
			(layer "B.Fab")
		)
		(fp_line
			(start -1.1049 0.724916)
			(end -1.1049 -0.724916)
			(stroke
				(width 0.1)
				(type default)
			)
			(layer "B.Fab")
		)
		(fp_line
			(start -1.1049 -0.724916)
			(end 1.1049 -0.724916)
			(stroke
				(width 0.1)
				(type default)
			)
			(layer "B.Fab")
		)
		(pad "1" smd rect
			(at 0.889 0 180)
			(size 1.016 1.27)
			(layers "B.Cu" "B.Mask" "B.Paste")
			(net "PVDD18_S5_P1")
		)
		(pad "2" smd rect
			(at -0.889 0 180)
			(size 1.016 1.27)
			(layers "B.Cu" "B.Mask" "B.Paste")
			(net "GND")
		)
	)
	(footprint ""
		(layer "B.Cu")
		(at 156.355034 -199.234552 90)
		(property "Reference" "R524"
			(at 0 0 90)
			(layer "B.SilkS")
			(hide yes)
			(effects
				(font
					(size 1.27 1.27)
				)
				(justify mirror)
			)
		)
		(property "Value" ""
			(at 0 0 90)
			(layer "B.Fab")
			(effects
				(font
					(size 1.27 1.27)
				)
				(justify mirror)
			)
		)
		(duplicate_pad_numbers_are_jumpers no)
		(fp_line
			(start 0.7874 -0.4064)
			(end -0.7874 -0.4064)
			(stroke
				(width 0.1524)
				(type default)
			)
			(layer "B.SilkS")
		)
		(fp_line
			(start -0.7874 -0.4064)
			(end -0.7874 0.4064)
			(stroke
				(width 0.1524)
				(type default)
			)
			(layer "B.SilkS")
		)
		(fp_line
			(start 0.7874 0.4064)
			(end 0.7874 -0.4064)
			(stroke
				(width 0.1524)
				(type default)
			)
			(layer "B.SilkS")
		)
		(fp_line
			(start -0.7874 0.4064)
			(end 0.7874 0.4064)
			(stroke
				(width 0.1524)
				(type default)
			)
			(layer "B.SilkS")
		)
		(fp_line
			(start 0.67945 -0.305054)
			(end 0.12065 -0.305054)
			(stroke
				(width 0.1)
				(type default)
			)
			(layer "B.Fab")
		)
		(fp_line
			(start 0.12065 -0.305054)
			(end 0.12065 -0.2794)
			(stroke
				(width 0.1)
				(type default)
			)
			(layer "B.Fab")
		)
		(fp_line
			(start -0.12065 -0.3048)
			(end -0.67945 -0.3048)
			(stroke
				(width 0.1)
				(type default)
			)
			(layer "B.Fab")
		)
		(fp_line
			(start -0.67945 -0.3048)
			(end -0.67945 0.3048)
			(stroke
				(width 0.1)
				(type default)
			)
			(layer "B.Fab")
		)
		(fp_line
			(start 0.12065 -0.2794)
			(end -0.12065 -0.2794)
			(stroke
				(width 0.1)
				(type default)
			)
			(layer "B.Fab")
		)
		(fp_line
			(start -0.12065 -0.2794)
			(end -0.12065 -0.3048)
			(stroke
				(width 0.1)
				(type default)
			)
			(layer "B.Fab")
		)
		(fp_line
			(start 0.12065 0.2794)
			(end 0.12065 0.3048)
			(stroke
				(width 0.1)
				(type default)
			)
			(layer "B.Fab")
		)
		(fp_line
			(start -0.120396 0.2794)
			(end 0.12065 0.2794)
			(stroke
				(width 0.1)
				(type default)
			)
			(layer "B.Fab")
		)
		(fp_line
			(start 0.67945 0.3048)
			(end 0.67945 -0.305054)
			(stroke
				(width 0.1)
				(type default)
			)
			(layer "B.Fab")
		)
		(fp_line
			(start 0.12065 0.3048)
			(end 0.67945 0.3048)
			(stroke
				(width 0.1)
				(type default)
			)
			(layer "B.Fab")
		)
		(fp_line
			(start -0.120396 0.3048)
			(end -0.120396 0.2794)
			(stroke
				(width 0.1)
				(type default)
			)
			(layer "B.Fab")
		)
		(fp_line
			(start -0.67945 0.3048)
			(end -0.120396 0.3048)
			(stroke
				(width 0.1)
				(type default)
			)
			(layer "B.Fab")
		)
		(pad "1" smd circle
			(at 0.40005 0 270)
			(size 0 0)
			(layers "B.Cu" "B.Mask" "B.Paste")
			(net "PVDD18_S5_P1")
		)
		(pad "2" smd circle
			(at -0.40005 0 270)
			(size 0 0)
			(layers "B.Cu" "B.Mask" "B.Paste")
			(net "JTAG_CPU1_TDI")
		)
	)
	(footprint ""
		(layer "B.Cu")
		(at 122.891296 -390.560052 90)
		(property "Reference" "C438"
			(at 0 0 90)
			(layer "B.SilkS")
			(hide yes)
			(effects
				(font
					(size 1.27 1.27)
				)
				(justify mirror)
			)
		)
		(property "Value" ""
			(at 0 0 90)
			(layer "B.Fab")
			(effects
				(font
					(size 1.27 1.27)
				)
				(justify mirror)
			)
		)
		(duplicate_pad_numbers_are_jumpers no)
		(fp_line
			(start 0.7874 -0.4064)
			(end -0.7874 -0.4064)
			(stroke
				(width 0.1524)
				(type default)
			)
			(layer "B.SilkS")
		)
		(fp_line
			(start -0.7874 -0.4064)
			(end -0.7874 0.4064)
			(stroke
				(width 0.1524)
				(type default)
			)
			(layer "B.SilkS")
		)
		(fp_line
			(start 0.7874 0.4064)
			(end 0.7874 -0.4064)
			(stroke
				(width 0.1524)
				(type default)
			)
			(layer "B.SilkS")
		)
		(fp_line
			(start -0.7874 0.4064)
			(end 0.7874 0.4064)
			(stroke
				(width 0.1524)
				(type default)
			)
			(layer "B.SilkS")
		)
		(fp_line
			(start 0.67945 -0.305054)
			(end 0.12065 -0.305054)
			(stroke
				(width 0.1)
				(type default)
			)
			(layer "B.Fab")
		)
		(fp_line
			(start 0.12065 -0.305054)
			(end 0.12065 -0.2794)
			(stroke
				(width 0.1)
				(type default)
			)
			(layer "B.Fab")
		)
		(fp_line
			(start -0.12065 -0.3048)
			(end -0.67945 -0.3048)
			(stroke
				(width 0.1)
				(type default)
			)
			(layer "B.Fab")
		)
		(fp_line
			(start -0.67945 -0.3048)
			(end -0.67945 0.3048)
			(stroke
				(width 0.1)
				(type default)
			)
			(layer "B.Fab")
		)
		(fp_line
			(start 0.12065 -0.2794)
			(end -0.12065 -0.2794)
			(stroke
				(width 0.1)
				(type default)
			)
			(layer "B.Fab")
		)
		(fp_line
			(start -0.12065 -0.2794)
			(end -0.12065 -0.3048)
			(stroke
				(width 0.1)
				(type default)
			)
			(layer "B.Fab")
		)
		(fp_line
			(start 0.12065 0.2794)
			(end 0.12065 0.3048)
			(stroke
				(width 0.1)
				(type default)
			)
			(layer "B.Fab")
		)
		(fp_line
			(start -0.120396 0.2794)
			(end 0.12065 0.2794)
			(stroke
				(width 0.1)
				(type default)
			)
			(layer "B.Fab")
		)
		(fp_line
			(start 0.67945 0.3048)
			(end 0.67945 -0.305054)
			(stroke
				(width 0.1)
				(type default)
			)
			(layer "B.Fab")
		)
		(fp_line
			(start 0.12065 0.3048)
			(end 0.67945 0.3048)
			(stroke
				(width 0.1)
				(type default)
			)
			(layer "B.Fab")
		)
		(fp_line
			(start -0.120396 0.3048)
			(end -0.120396 0.2794)
			(stroke
				(width 0.1)
				(type default)
			)
			(layer "B.Fab")
		)
		(fp_line
			(start -0.67945 0.3048)
			(end -0.120396 0.3048)
			(stroke
				(width 0.1)
				(type default)
			)
			(layer "B.Fab")
		)
		(pad "1" smd circle
			(at 0.40005 0 270)
			(size 0 0)
			(layers "B.Cu" "B.Mask" "B.Paste")
			(net "P1V8_CPU1_RT3_1A")
		)
		(pad "2" smd circle
			(at -0.40005 0 270)
			(size 0 0)
			(layers "B.Cu" "B.Mask" "B.Paste")
			(net "GND")
		)
	)
	(footprint ""
		(layer "B.Cu")
		(at 47.37862 -386.766562 90)
		(property "Reference" "C135"
			(at 0 0 90)
			(layer "B.SilkS")
			(hide yes)
			(effects
				(font
					(size 1.27 1.27)
				)
				(justify mirror)
			)
		)
		(property "Value" ""
			(at 0 0 90)
			(layer "B.Fab")
			(effects
				(font
					(size 1.27 1.27)
				)
				(justify mirror)
			)
		)
		(duplicate_pad_numbers_are_jumpers no)
		(fp_line
			(start 0.299974 -0.150114)
			(end -0.299974 -0.150114)
			(stroke
				(width 0.1)
				(type default)
			)
			(layer "B.Fab")
		)
		(fp_line
			(start -0.299974 -0.150114)
			(end -0.299974 0.150114)
			(stroke
				(width 0.1)
				(type default)
			)
			(layer "B.Fab")
		)
		(fp_line
			(start 0.299974 0.150114)
			(end 0.299974 -0.150114)
			(stroke
				(width 0.1)
				(type default)
			)
			(layer "B.Fab")
		)
		(fp_line
			(start -0.299974 0.150114)
			(end 0.299974 0.150114)
			(stroke
				(width 0.1)
				(type default)
			)
			(layer "B.Fab")
		)
		(pad "1" smd rect
			(at 0.2667 0 270)
			(size 0.3048 0.381)
			(layers "B.Cu" "B.Mask" "B.Paste")
			(net "P0V9_CPU1_RT0_2A")
		)
		(pad "2" smd rect
			(at -0.2667 0 270)
			(size 0.3048 0.381)
			(layers "B.Cu" "B.Mask" "B.Paste")
			(net "GND")
		)
	)
)
